# T6G (Grand Teton) — schematic netlist excerpt (pin names and nets, part order shuffled) for the footprints in the layout excerpt that follows; sources: Cadence DE-HDL packaged netlist, KiCad conversion of 04192023_DAF0TMB3IC0_F0TG_MB_C_brd_V02_OCP.brd

R1009  Q_RES  10K 1% CHIP  pkg 0402LF  page 155 : A = P3V3_AUX ; B = IRQ_LVC3_WAKE
PC2153  Q_CAP  0.22UF 16V 10% X7R  pkg 0402  page 135 : A = P12V_OCP_TIMER_1 ; B = GND

(kicad_pcb
	(version 20260206)
	(generator "pcbnew")
	(generator_version "10.0")
	(general
		(thickness 1.6)
		(legacy_teardrops no)
	)
	(paper "A4")
	(title_block
		(title "04192023_DAF0TMB3IC0_F0TG_MB_C_brd_V02_OCP.brd")
		(comment 1 "Grand Teton / footprints 4784-4785 of 8354")
	)
	(layers
		(0 "F.Cu" signal "TOP")
		(4 "In1.Cu" signal "GND")
		(6 "In2.Cu" signal "IN1")
		(8 "In3.Cu" signal "GND1")
		(10 "In4.Cu" signal "IN2")
		(12 "In5.Cu" signal "GND2")
		(14 "In6.Cu" signal "IN3")
		(16 "In7.Cu" signal "GND3")
		(18 "In8.Cu" signal "VCC")
		(20 "In9.Cu" signal "VCC1")
		(22 "In10.Cu" signal "GND4")
		(24 "In11.Cu" signal "IN4")
		(26 "In12.Cu" signal "GND5")
		(28 "In13.Cu" signal "IN5")
		(30 "In14.Cu" signal "GND6")
		(32 "In15.Cu" signal "IN6")
		(34 "In16.Cu" signal "GND7")
		(2 "B.Cu" signal "BOTTOM")
		(9 "F.Adhes" user "F.Adhesive")
		(11 "B.Adhes" user "B.Adhesive")
		(13 "F.Paste" user "Package Geometry/Pastemask Top")
		(15 "B.Paste" user "Package Geometry/Pastemask Bottom")
		(5 "F.SilkS" user "Ref Des/Silkscreen Top")
		(7 "B.SilkS" user "Ref Des/Silkscreen Bottom")
		(1 "F.Mask" user "Board Geometry/Soldermask Top")
		(3 "B.Mask" user "Board Geometry/Soldermask Bottom")
		(17 "Dwgs.User" user "User.Drawings")
		(19 "Cmts.User" user "User.Comments")
		(21 "Eco1.User" user "User.Eco1")
		(23 "Eco2.User" user "User.Eco2")
		(25 "Edge.Cuts" user "Board Geometry/Outline")
		(27 "Margin" user)
		(31 "F.CrtYd" user "Package Geometry/Place Bound Top")
		(29 "B.CrtYd" user "Package Geometry/Place Bound Bottom")
		(35 "F.Fab" user "Ref Des/Assembly Top")
		(33 "B.Fab" user "Ref Des/Assembly Bottom")
	)
	(footprint ""
		(layer "F.Cu")
		(at 443.717172 -32.173418 90)
		(property "Reference" "PC2153"
			(at 0 0 90)
			(layer "F.SilkS")
			(hide yes)
			(effects
				(font
					(size 1.27 1.27)
				)
			)
		)
		(property "Value" ""
			(at 0 0 90)
			(layer "F.Fab")
			(effects
				(font
					(size 1.27 1.27)
				)
			)
		)
		(duplicate_pad_numbers_are_jumpers no)
		(fp_line
			(start 0.7874 -0.4064)
			(end 0.7874 0.4064)
			(stroke
				(width 0.1524)
				(type default)
			)
			(layer "F.SilkS")
		)
		(fp_line
			(start -0.7874 -0.4064)
			(end 0.7874 -0.4064)
			(stroke
				(width 0.1524)
				(type default)
			)
			(layer "F.SilkS")
		)
		(fp_line
			(start 0.7874 0.4064)
			(end -0.7874 0.4064)
			(stroke
				(width 0.1524)
				(type default)
			)
			(layer "F.SilkS")
		)
		(fp_line
			(start -0.7874 0.4064)
			(end -0.7874 -0.4064)
			(stroke
				(width 0.1524)
				(type default)
			)
			(layer "F.SilkS")
		)
		(fp_line
			(start -0.12065 -0.305054)
			(end -0.12065 -0.2794)
			(stroke
				(width 0.1)
				(type default)
			)
			(layer "F.Fab")
		)
		(fp_line
			(start -0.67945 -0.305054)
			(end -0.12065 -0.305054)
			(stroke
				(width 0.1)
				(type default)
			)
			(layer "F.Fab")
		)
		(fp_line
			(start 0.67945 -0.3048)
			(end 0.67945 0.3048)
			(stroke
				(width 0.1)
				(type default)
			)
			(layer "F.Fab")
		)
		(fp_line
			(start 0.12065 -0.3048)
			(end 0.67945 -0.3048)
			(stroke
				(width 0.1)
				(type default)
			)
			(layer "F.Fab")
		)
		(fp_line
			(start 0.12065 -0.2794)
			(end 0.12065 -0.3048)
			(stroke
				(width 0.1)
				(type default)
			)
			(layer "F.Fab")
		)
		(fp_line
			(start -0.12065 -0.2794)
			(end 0.12065 -0.2794)
			(stroke
				(width 0.1)
				(type default)
			)
			(layer "F.Fab")
		)
		(fp_line
			(start 0.120396 0.2794)
			(end -0.12065 0.2794)
			(stroke
				(width 0.1)
				(type default)
			)
			(layer "F.Fab")
		)
		(fp_line
			(start -0.12065 0.2794)
			(end -0.12065 0.3048)
			(stroke
				(width 0.1)
				(type default)
			)
			(layer "F.Fab")
		)
		(fp_line
			(start 0.67945 0.3048)
			(end 0.120396 0.3048)
			(stroke
				(width 0.1)
				(type default)
			)
			(layer "F.Fab")
		)
		(fp_line
			(start 0.120396 0.3048)
			(end 0.120396 0.2794)
			(stroke
				(width 0.1)
				(type default)
			)
			(layer "F.Fab")
		)
		(fp_line
			(start -0.12065 0.3048)
			(end -0.67945 0.3048)
			(stroke
				(width 0.1)
				(type default)
			)
			(layer "F.Fab")
		)
		(fp_line
			(start -0.67945 0.3048)
			(end -0.67945 -0.305054)
			(stroke
				(width 0.1)
				(type default)
			)
			(layer "F.Fab")
		)
		(pad "1" smd circle
			(at -0.40005 0 90)
			(size 0 0)
			(layers "F.Cu" "F.Mask" "F.Paste")
			(net "P12V_OCP_TIMER_1")
		)
		(pad "2" smd circle
			(at 0.40005 0 90)
			(size 0 0)
			(layers "F.Cu" "F.Mask" "F.Paste")
			(net "GND")
		)
	)
	(footprint ""
		(layer "F.Cu")
		(at 165.14064 -78.000606 180)
		(property "Reference" "R1009"
			(at 0 0 180)
			(layer "F.SilkS")
			(hide yes)
			(effects
				(font
					(size 1.27 1.27)
				)
			)
		)
		(property "Value" ""
			(at 0 0 180)
			(layer "F.Fab")
			(effects
				(font
					(size 1.27 1.27)
				)
			)
		)
		(duplicate_pad_numbers_are_jumpers no)
		(fp_line
			(start 0.7874 0.4064)
			(end -0.7874 0.4064)
			(stroke
				(width 0.1524)
				(type default)
			)
			(layer "F.SilkS")
		)
		(fp_line
			(start 0.7874 -0.4064)
			(end 0.7874 0.4064)
			(stroke
				(width 0.1524)
				(type default)
			)
			(layer "F.SilkS")
		)
		(fp_line
			(start -0.7874 0.4064)
			(end -0.7874 -0.4064)
			(stroke
				(width 0.1524)
				(type default)
			)
			(layer "F.SilkS")
		)
		(fp_line
			(start -0.7874 -0.4064)
			(end 0.7874 -0.4064)
			(stroke
				(width 0.1524)
				(type default)
			)
			(layer "F.SilkS")
		)
		(fp_line
			(start 0.67945 0.3048)
			(end 0.120396 0.3048)
			(stroke
				(width 0.1)
				(type default)
			)
			(layer "F.Fab")
		)
		(fp_line
			(start 0.67945 -0.3048)
			(end 0.67945 0.3048)
			(stroke
				(width 0.1)
				(type default)
			)
			(layer "F.Fab")
		)
		(fp_line
			(start 0.12065 -0.2794)
			(end 0.12065 -0.3048)
			(stroke
				(width 0.1)
				(type default)
			)
			(layer "F.Fab")
		)
		(fp_line
			(start 0.12065 -0.3048)
			(end 0.67945 -0.3048)
			(stroke
				(width 0.1)
				(type default)
			)
			(layer "F.Fab")
		)
		(fp_line
			(start 0.120396 0.3048)
			(end 0.120396 0.2794)
			(stroke
				(width 0.1)
				(type default)
			)
			(layer "F.Fab")
		)
		(fp_line
			(start 0.120396 0.2794)
			(end -0.12065 0.2794)
			(stroke
				(width 0.1)
				(type default)
			)
			(layer "F.Fab")
		)
		(fp_line
			(start -0.12065 0.3048)
			(end -0.67945 0.3048)
			(stroke
				(width 0.1)
				(type default)
			)
			(layer "F.Fab")
		)
		(fp_line
			(start -0.12065 0.2794)
			(end -0.12065 0.3048)
			(stroke
				(width 0.1)
				(type default)
			)
			(layer "F.Fab")
		)
		(fp_line
			(start -0.12065 -0.2794)
			(end 0.12065 -0.2794)
			(stroke
				(width 0.1)
				(type default)
			)
			(layer "F.Fab")
		)
		(fp_line
			(start -0.12065 -0.305054)
			(end -0.12065 -0.2794)
			(stroke
				(width 0.1)
				(type default)
			)
			(layer "F.Fab")
		)
		(fp_line
			(start -0.67945 0.3048)
			(end -0.67945 -0.305054)
			(stroke
				(width 0.1)
				(type default)
			)
			(layer "F.Fab")
		)
		(fp_line
			(start -0.67945 -0.305054)
			(end -0.12065 -0.305054)
			(stroke
				(width 0.1)
				(type default)
			)
			(layer "F.Fab")
		)
		(pad "1" smd circle
			(at -0.40005 0 180)
			(size 0 0)
			(layers "F.Cu" "F.Mask" "F.Paste")
			(net "P3V3_AUX")
		)
		(pad "2" smd circle
			(at 0.40005 0 180)
			(size 0 0)
			(layers "F.Cu" "F.Mask" "F.Paste")
			(net "IRQ_LVC3_WAKE")
		)
	)
)
